FILE_TYPE = MULTI_PHYS_TABLE;

PART 'SOLDER_PREFORM'
CLASS=IO

{========================================================================================}
:CLS_PN          = JEDEC_TYPE                 | ALT_SYMBOLS                  | DESCRIPTION                        ;
{========================================================================================}
 'G380-10015-01' = '0201_SOLDER_PREFORM_4MIL' | '(0201_SOLDER_PREFORM_5MIL)' | 'SOLDER PREFORM,ALLOY SAC305,0201'

END_PART

END.

